(kicad_pcb
	(version 20260206)
	(generator "pcbnew")
	(generator_version "10.0")
	(general
		(thickness 1.6)
		(legacy_teardrops no)
	)
	(paper "A4")
	(title_block
		(title "baseboard — 13948-1b.1110WZS1818.brd")
		(comment 1 "Honey Badger (Wiwynn) / footprints 1-9 of 2523")
	)
	(layers
		(0 "F.Cu" signal "TOP")
		(4 "In1.Cu" signal "L2GND")
		(6 "In2.Cu" signal "L3")
		(8 "In3.Cu" signal "L4VCC")
		(10 "In4.Cu" signal "L5VCC")
		(12 "In5.Cu" signal "L6")
		(14 "In6.Cu" signal "L7GND")
		(2 "B.Cu" signal "BOTTOM")
		(9 "F.Adhes" user "F.Adhesive")
		(11 "B.Adhes" user "B.Adhesive")
		(13 "F.Paste" user "Package Geometry/Pastemask Top")
		(15 "B.Paste" user "Package Geometry/Pastemask Bottom")
		(5 "F.SilkS" user "Ref Des/Silkscreen Top")
		(7 "B.SilkS" user "Ref Des/Silkscreen Bottom")
		(1 "F.Mask" user "Board Geometry/Soldermask Top")
		(3 "B.Mask" user "Board Geometry/Soldermask Bottom")
		(17 "Dwgs.User" user "User.Drawings")
		(19 "Cmts.User" user "User.Comments")
		(21 "Eco1.User" user "User.Eco1")
		(23 "Eco2.User" user "User.Eco2")
		(25 "Edge.Cuts" user "Board Geometry/Outline")
		(27 "Margin" user)
		(31 "F.CrtYd" user "Package Geometry/Place Bound Top")
		(29 "B.CrtYd" user "Package Geometry/Place Bound Bottom")
		(35 "F.Fab" user "Ref Des/Assembly Top")
		(33 "B.Fab" user "Ref Des/Assembly Bottom")
	)
	(footprint ""
		(layer "F.Cu")
		(at 289.433 -162.433)
		(property "Reference" "TP140"
			(at 0 0 0)
			(layer "F.SilkS")
			(hide yes)
			(effects
				(font
					(size 1.27 1.27)
				)
			)
		)
		(property "Value" "TPAD28"
			(at 0.0127 -1.8034 0)
			(unlocked yes)
			(layer "F.Fab")
			(hide yes)
			(effects
				(font
					(size 1.016 1.016)
					(thickness 0.1524)
				)
			)
		)
		(property "Device Type" "TPAD28"
			(at 0.0127 -3.3274 0)
			(unlocked yes)
			(layer "F.Fab")
			(hide yes)
			(effects
				(font
					(size 1.016 1.016)
					(thickness 0.1524)
				)
			)
		)
		(duplicate_pad_numbers_are_jumpers no)
		(fp_poly
			(pts
				(arc
					(start 0.3556 0)
					(mid -0.3556 0)
					(end 0.3556 0)
				)
			)
			(stroke
				(width 0)
				(type default)
			)
			(fill no)
			(layer "F.CrtYd")
		)
		(fp_poly
			(pts
				(arc
					(start 0.6096 0)
					(mid -0.6096 0)
					(end 0.6096 0)
				)
			)
			(stroke
				(width 0)
				(type default)
			)
			(fill no)
			(layer "F.Fab")
		)
		(pad "1" smd circle
			(at 0 0)
			(size 0.7112 0.7112)
			(layers "F.Cu" "F.Mask" "F.Paste")
			(net "TP_BMC_GPIOE3")
		)
	)
	(footprint ""
		(layer "F.Cu")
		(at 292.0746 -153.5938 -90)
		(property "Reference" "C232"
			(at 0 0 270)
			(layer "F.SilkS")
			(hide yes)
			(effects
				(font
					(size 1.27 1.27)
				)
			)
		)
		(property "Value" "SC1U6D3V3KX-2GP"
			(at 0 -2.8194 270)
			(unlocked yes)
			(layer "F.Fab")
			(hide yes)
			(effects
				(font
					(size 1.016 1.016)
					(thickness 0.1524)
				)
			)
		)
		(property "Device Type" "C603H36"
			(at 0 -4.3434 270)
			(unlocked yes)
			(layer "F.Fab")
			(hide yes)
			(effects
				(font
					(size 1.016 1.016)
					(thickness 0.1524)
				)
			)
		)
		(duplicate_pad_numbers_are_jumpers no)
		(fp_line
			(start 0.508 0)
			(end -0.508 0)
			(stroke
				(width 0.2032)
				(type default)
			)
			(layer "F.SilkS")
		)
		(fp_rect
			(start -0.5842 1.3335)
			(end 0.5842 -1.3335)
			(stroke
				(width 0)
				(type default)
			)
			(fill no)
			(layer "F.CrtYd")
		)
		(fp_rect
			(start -0.5842 1.3335)
			(end 0.5842 -1.3335)
			(stroke
				(width 0)
				(type default)
			)
			(fill no)
			(layer "F.Fab")
		)
		(pad "1" smd custom
			(at 0 -0.762 270)
			(size 0.2159 0.2159)
			(layers "F.Cu" "F.Mask" "F.Paste")
			(net "P3V3_STBY")
			(options
				(clearance outline)
				(anchor circle)
			)
			(primitives
				(gr_poly
					(pts
						(arc
							(start -0.3302 -0.4318)
							(mid -0.402042 -0.402042)
							(end -0.4318 -0.3302)
						)
						(arc
							(start -0.4318 0.3302)
							(mid -0.402042 0.402042)
							(end -0.3302 0.4318)
						)
						(arc
							(start 0.3302 0.4318)
							(mid 0.402042 0.402042)
							(end 0.4318 0.3302)
						)
						(arc
							(start 0.4318 -0.3302)
							(mid 0.402042 -0.402042)
							(end 0.3302 -0.4318)
						)
					)
					(width 0)
					(fill yes)
				)
			)
		)
		(pad "2" smd custom
			(at 0 0.762 270)
			(size 0.2159 0.2159)
			(layers "F.Cu" "F.Mask" "F.Paste")
			(net "GND")
			(options
				(clearance outline)
				(anchor circle)
			)
			(primitives
				(gr_poly
					(pts
						(arc
							(start -0.3302 -0.4318)
							(mid -0.402042 -0.402042)
							(end -0.4318 -0.3302)
						)
						(arc
							(start -0.4318 0.3302)
							(mid -0.402042 0.402042)
							(end -0.3302 0.4318)
						)
						(arc
							(start 0.3302 0.4318)
							(mid 0.402042 0.402042)
							(end 0.4318 0.3302)
						)
						(arc
							(start 0.4318 -0.3302)
							(mid 0.402042 -0.402042)
							(end 0.3302 -0.4318)
						)
					)
					(width 0)
					(fill yes)
				)
			)
		)
	)
	(footprint ""
		(layer "F.Cu")
		(at 116.586 -76.708)
		(property "Reference" "STP104"
			(at 0 0 0)
			(layer "F.SilkS")
			(hide yes)
			(effects
				(font
					(size 1.27 1.27)
				)
			)
		)
		(property "Value" "TPAD28"
			(at 0.0127 -1.8034 0)
			(unlocked yes)
			(layer "F.Fab")
			(hide yes)
			(effects
				(font
					(size 1.016 1.016)
					(thickness 0.1524)
				)
			)
		)
		(property "Device Type" "TPAD28"
			(at 0.0127 -3.3274 0)
			(unlocked yes)
			(layer "F.Fab")
			(hide yes)
			(effects
				(font
					(size 1.016 1.016)
					(thickness 0.1524)
				)
			)
		)
		(duplicate_pad_numbers_are_jumpers no)
		(fp_poly
			(pts
				(arc
					(start 0.3556 0)
					(mid -0.3556 0)
					(end 0.3556 0)
				)
			)
			(stroke
				(width 0)
				(type default)
			)
			(fill no)
			(layer "F.CrtYd")
		)
		(fp_poly
			(pts
				(arc
					(start 0.6096 0)
					(mid -0.6096 0)
					(end 0.6096 0)
				)
			)
			(stroke
				(width 0)
				(type default)
			)
			(fill no)
			(layer "F.Fab")
		)
		(pad "1" smd circle
			(at 0 0)
			(size 0.7112 0.7112)
			(layers "F.Cu" "F.Mask" "F.Paste")
			(net "TEST_MUX_37")
		)
	)
	(footprint ""
		(layer "F.Cu")
		(at 136.271 -98.806 180)
		(property "Reference" "SC1267"
			(at 0 0 180)
			(layer "F.SilkS")
			(hide yes)
			(effects
				(font
					(size 1.27 1.27)
				)
			)
		)
		(property "Value" "SCD01U10V1KX-GP"
			(at -2.8321 -1.7399 180)
			(unlocked yes)
			(layer "F.Fab")
			(hide yes)
			(effects
				(font
					(size 1.016 1.016)
					(thickness 0.1524)
				)
			)
		)
		(property "Device Type" "C0201H13"
			(at -2.8321 -3.2639 180)
			(unlocked yes)
			(layer "F.Fab")
			(hide yes)
			(effects
				(font
					(size 1.016 1.016)
					(thickness 0.1524)
				)
			)
		)
		(duplicate_pad_numbers_are_jumpers no)
		(fp_rect
			(start -0.2794 0.6477)
			(end 0.2794 -0.6477)
			(stroke
				(width 0)
				(type default)
			)
			(fill no)
			(layer "F.CrtYd")
		)
		(fp_rect
			(start -0.2794 0.6477)
			(end 0.2794 -0.6477)
			(stroke
				(width 0)
				(type default)
			)
			(fill no)
			(layer "F.Fab")
		)
		(pad "1" smd custom
			(at 0 -0.2794 180)
			(size 0.0762 0.0762)
			(layers "F.Cu" "F.Mask" "F.Paste")
			(net "3X24_SAS_TX20_N")
			(options
				(clearance outline)
				(anchor circle)
			)
			(primitives
				(gr_poly
					(pts
						(arc
							(start 0.1524 -0.127)
							(mid 0.137521 -0.162921)
							(end 0.1016 -0.1778)
						)
						(arc
							(start -0.1016 -0.1778)
							(mid -0.137521 -0.162921)
							(end -0.1524 -0.127)
						)
						(arc
							(start -0.1524 0.127)
							(mid -0.137521 0.162921)
							(end -0.1016 0.1778)
						)
						(arc
							(start 0.1016 0.1778)
							(mid 0.137521 0.162921)
							(end 0.1524 0.127)
						)
					)
					(width 0)
					(fill yes)
				)
			)
		)
		(pad "2" smd custom
			(at 0 0.2794 180)
			(size 0.0762 0.0762)
			(layers "F.Cu" "F.Mask" "F.Paste")
			(net "SAS_EXP_GF_TX_DN0")
			(options
				(clearance outline)
				(anchor circle)
			)
			(primitives
				(gr_poly
					(pts
						(arc
							(start 0.1524 -0.127)
							(mid 0.137521 -0.162921)
							(end 0.1016 -0.1778)
						)
						(arc
							(start -0.1016 -0.1778)
							(mid -0.137521 -0.162921)
							(end -0.1524 -0.127)
						)
						(arc
							(start -0.1524 0.127)
							(mid -0.137521 0.162921)
							(end -0.1016 0.1778)
						)
						(arc
							(start 0.1016 0.1778)
							(mid 0.137521 0.162921)
							(end 0.1524 0.127)
						)
					)
					(width 0)
					(fill yes)
				)
			)
		)
	)
	(footprint ""
		(layer "F.Cu")
		(at 152.247092 -100.359464 -90)
		(property "Reference" "SL16"
			(at 0 0 270)
			(layer "F.SilkS")
			(hide yes)
			(effects
				(font
					(size 1.27 1.27)
				)
			)
		)
		(property "Value" "MPZ2012S300AT-GP"
			(at 0 -4.2418 270)
			(unlocked yes)
			(layer "F.Fab")
			(hide yes)
			(effects
				(font
					(size 1.016 1.016)
					(thickness 0.1524)
				)
			)
		)
		(property "Device Type" "L805H42"
			(at 0 -5.7912 270)
			(unlocked yes)
			(layer "F.Fab")
			(hide yes)
			(effects
				(font
					(size 1.016 1.016)
					(thickness 0.1524)
				)
			)
		)
		(duplicate_pad_numbers_are_jumpers no)
		(fp_line
			(start -0.889 1.7018)
			(end -0.889 -1.7018)
			(stroke
				(width 0.1524)
				(type default)
			)
			(layer "F.SilkS")
		)
		(fp_line
			(start 0.889 1.7018)
			(end -0.889 1.7018)
			(stroke
				(width 0.1524)
				(type default)
			)
			(layer "F.SilkS")
		)
		(fp_line
			(start -0.889 -1.7018)
			(end 0.889 -1.7018)
			(stroke
				(width 0.1524)
				(type default)
			)
			(layer "F.SilkS")
		)
		(fp_line
			(start 0.889 -1.7018)
			(end 0.889 1.7018)
			(stroke
				(width 0.1524)
				(type default)
			)
			(layer "F.SilkS")
		)
		(fp_rect
			(start -0.9652 1.778)
			(end 0.9652 -1.778)
			(stroke
				(width 0)
				(type default)
			)
			(fill no)
			(layer "F.CrtYd")
		)
		(fp_rect
			(start -0.9652 1.778)
			(end 0.9652 -1.778)
			(stroke
				(width 0)
				(type default)
			)
			(fill no)
			(layer "F.Fab")
		)
		(pad "1" smd rect
			(at 0 -0.9652 270)
			(size 1.397 1.143)
			(layers "F.Cu" "F.Mask" "F.Paste")
			(net "P0V9_E")
		)
		(pad "2" smd rect
			(at 0 0.9652 270)
			(size 1.397 1.143)
			(layers "F.Cu" "F.Mask" "F.Paste")
			(net "GB_VDDA")
		)
	)
	(footprint ""
		(layer "F.Cu")
		(at 118.364 -34.798)
		(property "Reference" "STP13"
			(at 0 0 0)
			(layer "F.SilkS")
			(hide yes)
			(effects
				(font
					(size 1.27 1.27)
				)
			)
		)
		(property "Value" "TPAD28"
			(at 0.0127 -1.8034 0)
			(unlocked yes)
			(layer "F.Fab")
			(hide yes)
			(effects
				(font
					(size 1.016 1.016)
					(thickness 0.1524)
				)
			)
		)
		(property "Device Type" "TPAD28"
			(at 0.0127 -3.3274 0)
			(unlocked yes)
			(layer "F.Fab")
			(hide yes)
			(effects
				(font
					(size 1.016 1.016)
					(thickness 0.1524)
				)
			)
		)
		(duplicate_pad_numbers_are_jumpers no)
		(fp_poly
			(pts
				(arc
					(start 0.3556 0)
					(mid -0.3556 0)
					(end 0.3556 0)
				)
			)
			(stroke
				(width 0)
				(type default)
			)
			(fill no)
			(layer "F.CrtYd")
		)
		(fp_poly
			(pts
				(arc
					(start 0.6096 0)
					(mid -0.6096 0)
					(end 0.6096 0)
				)
			)
			(stroke
				(width 0)
				(type default)
			)
			(fill no)
			(layer "F.Fab")
		)
		(pad "1" smd circle
			(at 0 0)
			(size 0.7112 0.7112)
			(layers "F.Cu" "F.Mask" "F.Paste")
			(net "IOC_GPIO_31")
		)
	)
	(footprint ""
		(layer "F.Cu")
		(at 79.4766 -14.4018 90)
		(property "Reference" "PC210"
			(at 0 0 90)
			(layer "F.SilkS")
			(hide yes)
			(effects
				(font
					(size 1.27 1.27)
				)
			)
		)
		(property "Value" "SCD01U50V3KX-4GP"
			(at 0 -2.8194 90)
			(unlocked yes)
			(layer "F.Fab")
			(hide yes)
			(effects
				(font
					(size 1.016 1.016)
					(thickness 0.1524)
				)
			)
		)
		(property "Device Type" "C603H36"
			(at 0 -4.3434 90)
			(unlocked yes)
			(layer "F.Fab")
			(hide yes)
			(effects
				(font
					(size 1.016 1.016)
					(thickness 0.1524)
				)
			)
		)
		(duplicate_pad_numbers_are_jumpers no)
		(fp_line
			(start 0.508 0)
			(end -0.508 0)
			(stroke
				(width 0.2032)
				(type default)
			)
			(layer "F.SilkS")
		)
		(fp_rect
			(start -0.5842 1.3335)
			(end 0.5842 -1.3335)
			(stroke
				(width 0)
				(type default)
			)
			(fill no)
			(layer "F.CrtYd")
		)
		(fp_rect
			(start -0.5842 1.3335)
			(end 0.5842 -1.3335)
			(stroke
				(width 0)
				(type default)
			)
			(fill no)
			(layer "F.Fab")
		)
		(pad "1" smd custom
			(at 0 -0.762 90)
			(size 0.2159 0.2159)
			(layers "F.Cu" "F.Mask" "F.Paste")
			(net "VT235_VDDH")
			(options
				(clearance outline)
				(anchor circle)
			)
			(primitives
				(gr_poly
					(pts
						(arc
							(start -0.3302 -0.4318)
							(mid -0.402042 -0.402042)
							(end -0.4318 -0.3302)
						)
						(arc
							(start -0.4318 0.3302)
							(mid -0.402042 0.402042)
							(end -0.3302 0.4318)
						)
						(arc
							(start 0.3302 0.4318)
							(mid 0.402042 0.402042)
							(end 0.4318 0.3302)
						)
						(arc
							(start 0.4318 -0.3302)
							(mid 0.402042 -0.402042)
							(end 0.3302 -0.4318)
						)
					)
					(width 0)
					(fill yes)
				)
			)
		)
		(pad "2" smd custom
			(at 0 0.762 90)
			(size 0.2159 0.2159)
			(layers "F.Cu" "F.Mask" "F.Paste")
			(net "GND")
			(options
				(clearance outline)
				(anchor circle)
			)
			(primitives
				(gr_poly
					(pts
						(arc
							(start -0.3302 -0.4318)
							(mid -0.402042 -0.402042)
							(end -0.4318 -0.3302)
						)
						(arc
							(start -0.4318 0.3302)
							(mid -0.402042 0.402042)
							(end -0.3302 0.4318)
						)
						(arc
							(start 0.3302 0.4318)
							(mid 0.402042 0.402042)
							(end 0.4318 0.3302)
						)
						(arc
							(start 0.4318 -0.3302)
							(mid 0.402042 -0.402042)
							(end 0.3302 -0.4318)
						)
					)
					(width 0)
					(fill yes)
				)
			)
		)
	)
	(footprint ""
		(layer "F.Cu")
		(at 93.345 -221.361)
		(property "Reference" "SC433"
			(at 0 0 0)
			(layer "F.SilkS")
			(hide yes)
			(effects
				(font
					(size 1.27 1.27)
				)
			)
		)
		(property "Value" "SCD1U16V2KX-3GP"
			(at 1.1811 -2.7051 0)
			(unlocked yes)
			(layer "F.Fab")
			(hide yes)
			(effects
				(font
					(size 1.016 1.016)
					(thickness 0.1524)
				)
			)
		)
		(property "Device Type" "C402H22"
			(at 1.1811 -4.2291 0)
			(unlocked yes)
			(layer "F.Fab")
			(hide yes)
			(effects
				(font
					(size 1.016 1.016)
					(thickness 0.1524)
				)
			)
		)
		(duplicate_pad_numbers_are_jumpers no)
		(fp_rect
			(start -0.4318 0.9525)
			(end 0.4318 -0.9525)
			(stroke
				(width 0)
				(type default)
			)
			(fill no)
			(layer "F.CrtYd")
		)
		(fp_rect
			(start -0.4318 0.9525)
			(end 0.4318 -0.9525)
			(stroke
				(width 0)
				(type default)
			)
			(fill no)
			(layer "F.Fab")
		)
		(pad "1" smd custom
			(at 0 -0.4445)
			(size 0.1524 0.1524)
			(layers "F.Cu" "F.Mask" "F.Paste")
			(net "P3V3_STBY")
			(options
				(clearance outline)
				(anchor circle)
			)
			(primitives
				(gr_poly
					(pts
						(arc
							(start 0.3048 -0.2032)
							(mid 0.275042 -0.275042)
							(end 0.2032 -0.3048)
						)
						(arc
							(start -0.2032 -0.3048)
							(mid -0.275042 -0.275042)
							(end -0.3048 -0.2032)
						)
						(arc
							(start -0.3048 0.2032)
							(mid -0.275042 0.275042)
							(end -0.2032 0.3048)
						)
						(arc
							(start 0.2032 0.3048)
							(mid 0.275042 0.275042)
							(end 0.3048 0.2032)
						)
					)
					(width 0)
					(fill yes)
				)
			)
		)
		(pad "2" smd custom
			(at 0 0.4445)
			(size 0.1524 0.1524)
			(layers "F.Cu" "F.Mask" "F.Paste")
			(net "GND")
			(options
				(clearance outline)
				(anchor circle)
			)
			(primitives
				(gr_poly
					(pts
						(arc
							(start 0.3048 -0.2032)
							(mid 0.275042 -0.275042)
							(end 0.2032 -0.3048)
						)
						(arc
							(start -0.2032 -0.3048)
							(mid -0.275042 -0.275042)
							(end -0.3048 -0.2032)
						)
						(arc
							(start -0.3048 0.2032)
							(mid -0.275042 0.275042)
							(end -0.2032 0.3048)
						)
						(arc
							(start 0.2032 0.3048)
							(mid 0.275042 0.275042)
							(end 0.3048 0.2032)
						)
					)
					(width 0)
					(fill yes)
				)
			)
		)
	)
	(footprint ""
		(layer "F.Cu")
		(at 295.7068 -191.8208)
		(property "Reference" "C185"
			(at 0 0 0)
			(layer "F.SilkS")
			(hide yes)
			(effects
				(font
					(size 1.27 1.27)
				)
			)
		)
		(property "Value" "SCD1U16V2KX-3GP"
			(at 1.1811 -2.7051 0)
			(unlocked yes)
			(layer "F.Fab")
			(hide yes)
			(effects
				(font
					(size 1.016 1.016)
					(thickness 0.1524)
				)
			)
		)
		(property "Device Type" "C402H22"
			(at 1.1811 -4.2291 0)
			(unlocked yes)
			(layer "F.Fab")
			(hide yes)
			(effects
				(font
					(size 1.016 1.016)
					(thickness 0.1524)
				)
			)
		)
		(duplicate_pad_numbers_are_jumpers no)
		(fp_rect
			(start -0.4318 0.9525)
			(end 0.4318 -0.9525)
			(stroke
				(width 0)
				(type default)
			)
			(fill no)
			(layer "F.CrtYd")
		)
		(fp_rect
			(start -0.4318 0.9525)
			(end 0.4318 -0.9525)
			(stroke
				(width 0)
				(type default)
			)
			(fill no)
			(layer "F.Fab")
		)
		(pad "1" smd custom
			(at 0 -0.4445)
			(size 0.1524 0.1524)
			(layers "F.Cu" "F.Mask" "F.Paste")
			(net "P1V53_STBY")
			(options
				(clearance outline)
				(anchor circle)
			)
			(primitives
				(gr_poly
					(pts
						(arc
							(start 0.3048 -0.2032)
							(mid 0.275042 -0.275042)
							(end 0.2032 -0.3048)
						)
						(arc
							(start -0.2032 -0.3048)
							(mid -0.275042 -0.275042)
							(end -0.3048 -0.2032)
						)
						(arc
							(start -0.3048 0.2032)
							(mid -0.275042 0.275042)
							(end -0.2032 0.3048)
						)
						(arc
							(start 0.2032 0.3048)
							(mid 0.275042 0.275042)
							(end 0.3048 0.2032)
						)
					)
					(width 0)
					(fill yes)
				)
			)
		)
		(pad "2" smd custom
			(at 0 0.4445)
			(size 0.1524 0.1524)
			(layers "F.Cu" "F.Mask" "F.Paste")
			(net "GND")
			(options
				(clearance outline)
				(anchor circle)
			)
			(primitives
				(gr_poly
					(pts
						(arc
							(start 0.3048 -0.2032)
							(mid 0.275042 -0.275042)
							(end 0.2032 -0.3048)
						)
						(arc
							(start -0.2032 -0.3048)
							(mid -0.275042 -0.275042)
							(end -0.3048 -0.2032)
						)
						(arc
							(start -0.3048 0.2032)
							(mid -0.275042 0.275042)
							(end -0.2032 0.3048)
						)
						(arc
							(start 0.2032 0.3048)
							(mid 0.275042 0.275042)
							(end 0.3048 0.2032)
						)
					)
					(width 0)
					(fill yes)
				)
			)
		)
	)
)
